# S9S_MB_2U (Grand Teton) — schematic netlist excerpt (pin names and nets, part order shuffled) for the footprints in the layout excerpt that follows; sources: Cadence DE-HDL packaged netlist, KiCad conversion of 03242023_DA0F0TMBIJ0_F0T_Motherboard_J_brd_V01_OCP.brd

R142  Q_RES  0 5% CHIP  pkg 0402LF  page 240 : A = PVNN_TERM_CPU0 ; B = PVCCIO_PECI_BMC
PR1728  Q_RES  8.87K 1% EMPTY  pkg 0402LF  page 294 : A = PVCCFA_EHV_CPU1_LSET1 ; B = GND

(kicad_pcb
	(version 20260206)
	(generator "pcbnew")
	(generator_version "10.0")
	(general
		(thickness 1.6)
		(legacy_teardrops no)
	)
	(paper "A4")
	(title_block
		(title "03242023_DA0F0TMBIJ0_F0T_Motherboard_J_brd_V01_OCP.brd")
		(comment 1 "Grand Teton / footprints 1055-1056 of 6105")
	)
	(layers
		(0 "F.Cu" signal "TOP")
		(4 "In1.Cu" signal "GND")
		(6 "In2.Cu" signal "IN1")
		(8 "In3.Cu" signal "GND1")
		(10 "In4.Cu" signal "IN2")
		(12 "In5.Cu" signal "GND2")
		(14 "In6.Cu" signal "IN3")
		(16 "In7.Cu" signal "GND3")
		(18 "In8.Cu" signal "VCC")
		(20 "In9.Cu" signal "VCC1")
		(22 "In10.Cu" signal "GND4")
		(24 "In11.Cu" signal "IN4")
		(26 "In12.Cu" signal "GND5")
		(28 "In13.Cu" signal "IN5")
		(30 "In14.Cu" signal "GND6")
		(32 "In15.Cu" signal "IN6")
		(34 "In16.Cu" signal "GND7")
		(2 "B.Cu" signal "BOTTOM")
		(9 "F.Adhes" user "F.Adhesive")
		(11 "B.Adhes" user "B.Adhesive")
		(13 "F.Paste" user "Package Geometry/Pastemask Top")
		(15 "B.Paste" user "Package Geometry/Pastemask Bottom")
		(5 "F.SilkS" user "Ref Des/Silkscreen Top")
		(7 "B.SilkS" user "Ref Des/Silkscreen Bottom")
		(1 "F.Mask" user "Board Geometry/Soldermask Top")
		(3 "B.Mask" user "Board Geometry/Soldermask Bottom")
		(17 "Dwgs.User" user "User.Drawings")
		(19 "Cmts.User" user "User.Comments")
		(21 "Eco1.User" user "User.Eco1")
		(23 "Eco2.User" user "User.Eco2")
		(25 "Edge.Cuts" user "Board Geometry/Outline")
		(27 "Margin" user)
		(31 "F.CrtYd" user "Package Geometry/Place Bound Top")
		(29 "B.CrtYd" user "Package Geometry/Place Bound Bottom")
		(35 "F.Fab" user "Ref Des/Assembly Top")
		(33 "B.Fab" user "Ref Des/Assembly Bottom")
	)
	(footprint ""
		(layer "F.Cu")
		(at 54.112414 -171.129198)
		(property "Reference" "PR1728"
			(at 0 0 0)
			(layer "F.SilkS")
			(hide yes)
			(effects
				(font
					(size 1.27 1.27)
				)
			)
		)
		(property "Value" ""
			(at 0 0 0)
			(layer "F.Fab")
			(effects
				(font
					(size 1.27 1.27)
				)
			)
		)
		(duplicate_pad_numbers_are_jumpers no)
		(fp_line
			(start -0.7874 -0.4064)
			(end 0.7874 -0.4064)
			(stroke
				(width 0.1524)
				(type default)
			)
			(layer "F.SilkS")
		)
		(fp_line
			(start -0.7874 0.4064)
			(end -0.7874 -0.4064)
			(stroke
				(width 0.1524)
				(type default)
			)
			(layer "F.SilkS")
		)
		(fp_line
			(start 0.7874 -0.4064)
			(end 0.7874 0.4064)
			(stroke
				(width 0.1524)
				(type default)
			)
			(layer "F.SilkS")
		)
		(fp_line
			(start 0.7874 0.4064)
			(end -0.7874 0.4064)
			(stroke
				(width 0.1524)
				(type default)
			)
			(layer "F.SilkS")
		)
		(fp_line
			(start -0.67945 -0.305054)
			(end -0.12065 -0.305054)
			(stroke
				(width 0.1)
				(type default)
			)
			(layer "F.Fab")
		)
		(fp_line
			(start -0.67945 0.3048)
			(end -0.67945 -0.305054)
			(stroke
				(width 0.1)
				(type default)
			)
			(layer "F.Fab")
		)
		(fp_line
			(start -0.12065 -0.305054)
			(end -0.12065 -0.2794)
			(stroke
				(width 0.1)
				(type default)
			)
			(layer "F.Fab")
		)
		(fp_line
			(start -0.12065 -0.2794)
			(end 0.12065 -0.2794)
			(stroke
				(width 0.1)
				(type default)
			)
			(layer "F.Fab")
		)
		(fp_line
			(start -0.12065 0.2794)
			(end -0.12065 0.3048)
			(stroke
				(width 0.1)
				(type default)
			)
			(layer "F.Fab")
		)
		(fp_line
			(start -0.12065 0.3048)
			(end -0.67945 0.3048)
			(stroke
				(width 0.1)
				(type default)
			)
			(layer "F.Fab")
		)
		(fp_line
			(start 0.120396 0.2794)
			(end -0.12065 0.2794)
			(stroke
				(width 0.1)
				(type default)
			)
			(layer "F.Fab")
		)
		(fp_line
			(start 0.120396 0.3048)
			(end 0.120396 0.2794)
			(stroke
				(width 0.1)
				(type default)
			)
			(layer "F.Fab")
		)
		(fp_line
			(start 0.12065 -0.3048)
			(end 0.67945 -0.3048)
			(stroke
				(width 0.1)
				(type default)
			)
			(layer "F.Fab")
		)
		(fp_line
			(start 0.12065 -0.2794)
			(end 0.12065 -0.3048)
			(stroke
				(width 0.1)
				(type default)
			)
			(layer "F.Fab")
		)
		(fp_line
			(start 0.67945 -0.3048)
			(end 0.67945 0.3048)
			(stroke
				(width 0.1)
				(type default)
			)
			(layer "F.Fab")
		)
		(fp_line
			(start 0.67945 0.3048)
			(end 0.120396 0.3048)
			(stroke
				(width 0.1)
				(type default)
			)
			(layer "F.Fab")
		)
		(pad "1" smd circle
			(at -0.40005 0)
			(size 0 0)
			(layers "F.Cu" "F.Mask" "F.Paste")
			(net "PVCCFA_EHV_CPU1_LSET1")
		)
		(pad "2" smd circle
			(at 0.40005 0)
			(size 0 0)
			(layers "F.Cu" "F.Mask" "F.Paste")
			(net "GND")
		)
	)
	(footprint ""
		(layer "F.Cu")
		(at 164.67328 -21.783548 -90)
		(property "Reference" "R142"
			(at 0 0 270)
			(layer "F.SilkS")
			(hide yes)
			(effects
				(font
					(size 1.27 1.27)
				)
			)
		)
		(property "Value" ""
			(at 0 0 270)
			(layer "F.Fab")
			(effects
				(font
					(size 1.27 1.27)
				)
			)
		)
		(duplicate_pad_numbers_are_jumpers no)
		(fp_line
			(start -0.7874 0.4064)
			(end -0.7874 -0.4064)
			(stroke
				(width 0.1524)
				(type default)
			)
			(layer "F.SilkS")
		)
		(fp_line
			(start 0.7874 0.4064)
			(end -0.7874 0.4064)
			(stroke
				(width 0.1524)
				(type default)
			)
			(layer "F.SilkS")
		)
		(fp_line
			(start -0.7874 -0.4064)
			(end 0.7874 -0.4064)
			(stroke
				(width 0.1524)
				(type default)
			)
			(layer "F.SilkS")
		)
		(fp_line
			(start 0.7874 -0.4064)
			(end 0.7874 0.4064)
			(stroke
				(width 0.1524)
				(type default)
			)
			(layer "F.SilkS")
		)
		(fp_line
			(start -0.67945 0.3048)
			(end -0.67945 -0.305054)
			(stroke
				(width 0.1)
				(type default)
			)
			(layer "F.Fab")
		)
		(fp_line
			(start -0.12065 0.3048)
			(end -0.67945 0.3048)
			(stroke
				(width 0.1)
				(type default)
			)
			(layer "F.Fab")
		)
		(fp_line
			(start 0.120396 0.3048)
			(end 0.120396 0.2794)
			(stroke
				(width 0.1)
				(type default)
			)
			(layer "F.Fab")
		)
		(fp_line
			(start 0.67945 0.3048)
			(end 0.120396 0.3048)
			(stroke
				(width 0.1)
				(type default)
			)
			(layer "F.Fab")
		)
		(fp_line
			(start -0.12065 0.2794)
			(end -0.12065 0.3048)
			(stroke
				(width 0.1)
				(type default)
			)
			(layer "F.Fab")
		)
		(fp_line
			(start 0.120396 0.2794)
			(end -0.12065 0.2794)
			(stroke
				(width 0.1)
				(type default)
			)
			(layer "F.Fab")
		)
		(fp_line
			(start -0.12065 -0.2794)
			(end 0.12065 -0.2794)
			(stroke
				(width 0.1)
				(type default)
			)
			(layer "F.Fab")
		)
		(fp_line
			(start 0.12065 -0.2794)
			(end 0.12065 -0.3048)
			(stroke
				(width 0.1)
				(type default)
			)
			(layer "F.Fab")
		)
		(fp_line
			(start 0.12065 -0.3048)
			(end 0.67945 -0.3048)
			(stroke
				(width 0.1)
				(type default)
			)
			(layer "F.Fab")
		)
		(fp_line
			(start 0.67945 -0.3048)
			(end 0.67945 0.3048)
			(stroke
				(width 0.1)
				(type default)
			)
			(layer "F.Fab")
		)
		(fp_line
			(start -0.67945 -0.305054)
			(end -0.12065 -0.305054)
			(stroke
				(width 0.1)
				(type default)
			)
			(layer "F.Fab")
		)
		(fp_line
			(start -0.12065 -0.305054)
			(end -0.12065 -0.2794)
			(stroke
				(width 0.1)
				(type default)
			)
			(layer "F.Fab")
		)
		(pad "1" smd circle
			(at -0.40005 0 270)
			(size 0 0)
			(layers "F.Cu" "F.Mask" "F.Paste")
			(net "PVNN_TERM_CPU0")
		)
		(pad "2" smd circle
			(at 0.40005 0 270)
			(size 0 0)
			(layers "F.Cu" "F.Mask" "F.Paste")
			(net "PVCCIO_PECI_BMC")
		)
	)
)
